# T6G (Grand Teton) — schematic parts with pin connectivity, parts 8082–8082 of 8303; source: Cadence DE-HDL packaged netlist (pstxprt.dat, pstxnet.dat, pstchip.dat)

U26  GENOA_SP5  SOCKET6096_13568-001 IO  pkg SOCKET6096_93-4X120-45XA  page 37  (pins 4369-4704 of 6096)
  DA58  VSS_DA58  POWER  = GND
  DA59  MDB_DATA25  BI  = M_D_CPU1_SB_DQ<25>
  DA60  MDB_DATA26  BI  = M_D_CPU1_SB_DQ<26>
  DA61  VSS_DA61  POWER  = GND
  DA62  MBB_DATA25  BI  = M_B_CPU1_SB_DQ<25>
  DA63  VSS_DA63  POWER  = GND
  DA64  MBB_DATA26  BI  = M_B_CPU1_SB_DQ<26>
  DA65  VSS_DA65  POWER  = GND
  DA66  MFB_DATA25  BI  = M_F_CPU1_SB_DQ<25>
  DA67  MFB_DATA26  BI  = M_F_CPU1_SB_DQ<26>
  DA68  VSS_DA68  POWER  = GND
  DA69  MEB_DATA25  BI  = M_E_CPU1_SB_DQ<25>
  DA70  VSS_DA70  POWER  = GND
  DA71  MEB_DATA26  BI  = M_E_CPU1_SB_DQ<26>
  DA72  VSS_DA72  POWER  = GND
  DA73  MAB_DATA25  BI  = M_A_CPU1_SB_DQ<25>
  DA74  MAB_DATA26  BI  = M_A_CPU1_SB_DQ<26>
  DA75  VSS_DA75  POWER  = GND
  DB2  MGB_DQS_H3  BI  = M_G_CPU1_SB_DQS_DP<3>
  DB3  VSS_DB3  POWER  = GND
  DB4  MGB_DATA27  BI  = M_G_CPU1_SB_DQ<27>
  DB5  VDD_11_S3_DB5  POWER  = PVDD11_S3_P1
  DB6  MKB_DQS_H3  BI  = M_K_CPU1_SB_DQS_DP<3>
  DB7  MKB_DATA27  BI  = M_K_CPU1_SB_DQ<27>
  DB8  VSS_DB8  POWER  = GND
  DB9  MLB_DQS_H3  BI  = M_L_CPU1_SB_DQS_DP<3>
  DB10  VSS_DB10  POWER  = GND
  DB11  MLB_DATA27  BI  = M_L_CPU1_SB_DQ<27>
  DB12  VDD_11_S3_DB12  POWER  = PVDD11_S3_P1
  DB13  MHB_DQS_H3  BI  = M_H_CPU1_SB_DQS_DP<3>
  DB14  MHB_DATA27  BI  = M_H_CPU1_SB_DQ<27>
  DB15  VSS_DB15  POWER  = GND
  DB16  MJB_DQS_H3  BI  = M_J_CPU1_SB_DQS_DP<3>
  DB17  VSS_DB17  POWER  = GND
  DB18  MJB_DATA27  BI  = M_J_CPU1_SB_DQ<27>
  DB19  VDD_11_S3_DB19  POWER  = PVDD11_S3_P1
  DB20  MIB_DQS_H3  BI  = M_I_CPU1_SB_DQS_DP<3>
  DB21  MIB_DATA27  BI  = M_I_CPU1_SB_DQ<27>
  DB22  VSS_DB22  POWER  = GND
  DB23  VDDCR_CPU1_DB23  POWER  = PVDDCR_CPU1_P1
  DB24  VDDCR_CPU1_DB24  POWER  = PVDDCR_CPU1_P1
  DB25  VSS_DB25  POWER  = GND
  DB26  VDDCR_CPU1_DB26  POWER  = PVDDCR_CPU1_P1
  DB27  VDDCR_CPU1_DB27  POWER  = PVDDCR_CPU1_P1
  DB28  VSS_DB28  POWER  = GND
  DB29  VDDCR_CPU1_DB29  POWER  = PVDDCR_CPU1_P1
  DB30  VDDCR_CPU1_DB30  POWER  = PVDDCR_CPU1_P1
  DB31  VSS_DB31  POWER  = GND
  DB32  VDDCR_CPU1_DB32  POWER  = PVDDCR_CPU1_P1
  DB33  VDDCR_CPU1_DB33  POWER  = PVDDCR_CPU1_P1
  DB34  VSS_DB34  POWER  = GND
  DB35  P3_RXP2  IN  = P5E_CPU1_P3_RX_DP<2>
  DB36  P3_RXN2  IN  = P5E_CPU1_P3_RX_DN<2>
  DB37  VSS_DB37  POWER  = GND
  DB39  VSS_DB39  POWER  = GND
  DB40  P1_TXN13  OUT  = P5E_CPU1_P1_TX_DN<13>
  DB41  P1_TXP13  OUT  = P5E_CPU1_P1_TX_DP<13>
  DB42  VSS_DB42  POWER  = GND
  DB43  VDDCR_CPU1_DB43  POWER  = PVDDCR_CPU1_P1
  DB44  VDDCR_CPU1_DB44  POWER  = PVDDCR_CPU1_P1
  DB45  VSS_DB45  POWER  = GND
  DB46  VDDCR_CPU1_DB46  POWER  = PVDDCR_CPU1_P1
  DB47  VDDCR_CPU1_DB47  POWER  = PVDDCR_CPU1_P1
  DB48  VSS_DB48  POWER  = GND
  DB49  VDDCR_CPU1_DB49  POWER  = PVDDCR_CPU1_P1
  DB50  VDDCR_CPU1_DB50  POWER  = PVDDCR_CPU1_P1
  DB51  VSS_DB51  POWER  = GND
  DB52  VDDCR_CPU1_DB52  POWER  = PVDDCR_CPU1_P1
  DB53  VDDCR_CPU1_DB53  POWER  = PVDDCR_CPU1_P1
  DB54  VSS_DB54  POWER  = GND
  DB55  MCB_DATA27  BI  = M_C_CPU1_SB_DQ<27>
  DB56  MCB_DQS_H3  BI  = M_C_CPU1_SB_DQS_DP<3>
  DB57  VDDIO_DB57  POWER  = PVDDIO_P1
  DB58  MDB_DATA27  BI  = M_D_CPU1_SB_DQ<27>
  DB59  VSS_DB59  POWER  = GND
  DB60  MDB_DQS_H3  BI  = M_D_CPU1_SB_DQS_DP<3>
  DB61  VSS_DB61  POWER  = GND
  DB62  MBB_DATA27  BI  = M_B_CPU1_SB_DQ<27>
  DB63  MBB_DQS_H3  BI  = M_B_CPU1_SB_DQS_DP<3>
  DB64  VDDIO_DB64  POWER  = PVDDIO_P1
  DB65  MFB_DATA27  BI  = M_F_CPU1_SB_DQ<27>
  DB66  VSS_DB66  POWER  = GND
  DB67  MFB_DQS_H3  BI  = M_F_CPU1_SB_DQS_DP<3>
  DB68  VSS_DB68  POWER  = GND
  DB69  MEB_DATA27  BI  = M_E_CPU1_SB_DQ<27>
  DB70  MEB_DQS_H3  BI  = M_E_CPU1_SB_DQS_DP<3>
  DB71  VDDIO_DB71  POWER  = PVDDIO_P1
  DB72  MAB_DATA27  BI  = M_A_CPU1_SB_DQ<27>
  DB73  VSS_DB73  POWER  = GND
  DB74  MAB_DQS_H3  BI  = M_A_CPU1_SB_DQS_DP<3>
  DC1  VSS_DC1  POWER  = GND
  DC2  MGB_DQS_L3  BI  = M_G_CPU1_SB_DQS_DN<3>
  DC3  MGB_DQS_L8  BI  = M_G_CPU1_SB_DQS_DN<8>
  DC4  VSS_DC4  POWER  = GND
  DC5  MKB_DQS_L3  BI  = M_K_CPU1_SB_DQS_DN<3>
  DC6  VSS_DC6  POWER  = GND
  DC7  MKB_DQS_L8  BI  = M_K_CPU1_SB_DQS_DN<8>
  DC8  VSS_DC8  POWER  = GND
  DC9  MLB_DQS_L3  BI  = M_L_CPU1_SB_DQS_DN<3>
  DC10  MLB_DQS_L8  BI  = M_L_CPU1_SB_DQS_DN<8>
  DC11  VSS_DC11  POWER  = GND
  DC12  MHB_DQS_L3  BI  = M_H_CPU1_SB_DQS_DN<3>
  DC13  VSS_DC13  POWER  = GND
  DC14  MHB_DQS_L8  BI  = M_H_CPU1_SB_DQS_DN<8>
  DC15  VSS_DC15  POWER  = GND
  DC16  MJB_DQS_L3  BI  = M_J_CPU1_SB_DQS_DN<3>
  DC17  MJB_DQS_L8  BI  = M_J_CPU1_SB_DQS_DN<8>
  DC18  VSS_DC18  POWER  = GND
  DC19  MIB_DQS_L3  BI  = M_I_CPU1_SB_DQS_DN<3>
  DC20  VSS_DC20  POWER  = GND
  DC21  MIB_DQS_L8  BI  = M_I_CPU1_SB_DQS_DN<8>
  DC22  VSS_DC22  POWER  = GND
  DC23  P3_RXP13  IN  = P5E_CPU1_P3_RX_DP<13>
  DC24  P3_RXN13  IN  = P5E_CPU1_P3_RX_DN<13>
  DC25  VSS_DC25  POWER  = GND
  DC26  P3_RXP10  IN  = P5E_CPU1_P3_RX_DP<10>
  DC27  P3_RXN10  IN  = P5E_CPU1_P3_RX_DN<10>
  DC28  VSS_DC28  POWER  = GND
  DC29  P3_RXP7  IN  = P5E_CPU1_P3_RX_DP<7>
  DC30  P3_RXN7  IN  = P5E_CPU1_P3_RX_DN<7>
  DC31  VSS_DC31  POWER  = GND
  DC32  P3_RXP4  IN  = P5E_CPU1_P3_RX_DP<4>
  DC33  P3_RXN4  IN  = P5E_CPU1_P3_RX_DN<4>
  DC34  VSS_DC34  POWER  = GND
  DC35  VDDCR_CPU1_DC35  POWER  = PVDDCR_CPU1_P1
  DC36  VDDCR_CPU1_DC36  POWER  = PVDDCR_CPU1_P1
  DC40  VDDCR_CPU1_DC40  POWER  = PVDDCR_CPU1_P1
  DC41  VDDCR_CPU1_DC41  POWER  = PVDDCR_CPU1_P1
  DC42  VSS_DC42  POWER  = GND
  DC43  P1_TXN11  OUT  = P5E_CPU1_P1_TX_DN<11>
  DC44  P1_TXP11  OUT  = P5E_CPU1_P1_TX_DP<11>
  DC45  VSS_DC45  POWER  = GND
  DC46  P1_TXN8  OUT  = P5E_CPU1_P1_TX_DN<8>
  DC47  P1_TXP8  OUT  = P5E_CPU1_P1_TX_DP<8>
  DC48  VSS_DC48  POWER  = GND
  DC49  P1_TXN5  OUT  = P5E_CPU1_P1_TX_DN<5>
  DC50  P1_TXP5  OUT  = P5E_CPU1_P1_TX_DP<5>
  DC51  VSS_DC51  POWER  = GND
  DC52  P1_TXN2  OUT  = P5E_CPU1_P1_TX_DN<2>
  DC53  P1_TXP2  OUT  = P5E_CPU1_P1_TX_DP<2>
  DC54  VSS_DC54  POWER  = GND
  DC55  MCB_DQS_L8  BI  = M_C_CPU1_SB_DQS_DN<8>
  DC56  VSS_DC56  POWER  = GND
  DC57  MCB_DQS_L3  BI  = M_C_CPU1_SB_DQS_DN<3>
  DC58  VSS_DC58  POWER  = GND
  DC59  MDB_DQS_L8  BI  = M_D_CPU1_SB_DQS_DN<8>
  DC60  MDB_DQS_L3  BI  = M_D_CPU1_SB_DQS_DN<3>
  DC61  VSS_DC61  POWER  = GND
  DC62  MBB_DQS_L8  BI  = M_B_CPU1_SB_DQS_DN<8>
  DC63  VSS_DC63  POWER  = GND
  DC64  MBB_DQS_L3  BI  = M_B_CPU1_SB_DQS_DN<3>
  DC65  VSS_DC65  POWER  = GND
  DC66  MFB_DQS_L8  BI  = M_F_CPU1_SB_DQS_DN<8>
  DC67  MFB_DQS_L3  BI  = M_F_CPU1_SB_DQS_DN<3>
  DC68  VSS_DC68  POWER  = GND
  DC69  MEB_DQS_L8  BI  = M_E_CPU1_SB_DQS_DN<8>
  DC70  VSS_DC70  POWER  = GND
  DC71  MEB_DQS_L3  BI  = M_E_CPU1_SB_DQS_DN<3>
  DC72  VSS_DC72  POWER  = GND
  DC73  MAB_DQS_L8  BI  = M_A_CPU1_SB_DQS_DN<8>
  DC74  MAB_DQS_L3  BI  = M_A_CPU1_SB_DQS_DN<3>
  DC75  VSS_DC75  POWER  = GND
  DD2  MGB_DATA28  BI  = M_G_CPU1_SB_DQ<28>
  DD3  VSS_DD3  POWER  = GND
  DD4  MGB_DQS_H8  BI  = M_G_CPU1_SB_DQS_DP<8>
  DD5  VSS_DD5  POWER  = GND
  DD6  MKB_DATA28  BI  = M_K_CPU1_SB_DQ<28>
  DD7  MKB_DQS_H8  BI  = M_K_CPU1_SB_DQS_DP<8>
  DD8  VSS_DD8  POWER  = GND
  DD9  MLB_DATA28  BI  = M_L_CPU1_SB_DQ<28>
  DD10  VSS_DD10  POWER  = GND
  DD11  MLB_DQS_H8  BI  = M_L_CPU1_SB_DQS_DP<8>
  DD12  VSS_DD12  POWER  = GND
  DD13  MHB_DATA28  BI  = M_H_CPU1_SB_DQ<28>
  DD14  MHB_DQS_H8  BI  = M_H_CPU1_SB_DQS_DP<8>
  DD15  VSS_DD15  POWER  = GND
  DD16  MJB_DATA28  BI  = M_J_CPU1_SB_DQ<28>
  DD17  VSS_DD17  POWER  = GND
  DD18  MJB_DQS_H8  BI  = M_J_CPU1_SB_DQS_DP<8>
  DD19  VSS_DD19  POWER  = GND
  DD20  MIB_DATA28  BI  = M_I_CPU1_SB_DQ<28>
  DD21  MIB_DQS_H8  BI  = M_I_CPU1_SB_DQS_DP<8>
  DD22  VDDCR_CPU1_DD22  POWER  = PVDDCR_CPU1_P1
  DD23  VSS_DD23  POWER  = GND
  DD24  VSS_DD24  POWER  = GND
  DD25  VDDCR_CPU1_DD25  POWER  = PVDDCR_CPU1_P1
  DD26  VSS_DD26  POWER  = GND
  DD27  VSS_DD27  POWER  = GND
  DD28  VDDCR_CPU1_DD28  POWER  = PVDDCR_CPU1_P1
  DD29  VSS_DD29  POWER  = GND
  DD30  VSS_DD30  POWER  = GND
  DD31  VDDCR_CPU1_DD31  POWER  = PVDDCR_CPU1_P1
  DD32  VSS_DD32  POWER  = GND
  DD33  VSS_DD33  POWER  = GND
  DD34  VDDCR_CPU1_DD34  POWER  = PVDDCR_CPU1_P1
  DD35  VSS_DD35  POWER  = GND
  DD36  VSS_DD36  POWER  = GND
  DD37  VSS_DD37  POWER  = GND
  DD39  VSS_DD39  POWER  = GND
  DD40  VSS_DD40  POWER  = GND
  DD41  VSS_DD41  POWER  = GND
  DD42  VDDCR_CPU1_DD42  POWER  = PVDDCR_CPU1_P1
  DD43  VSS_DD43  POWER  = GND
  DD44  VSS_DD44  POWER  = GND
  DD45  VDDCR_CPU1_DD45  POWER  = PVDDCR_CPU1_P1
  DD46  VSS_DD46  POWER  = GND
  DD47  VSS_DD47  POWER  = GND
  DD48  VDDCR_CPU1_DD48  POWER  = PVDDCR_CPU1_P1
  DD49  VSS_DD49  POWER  = GND
  DD50  VSS_DD50  POWER  = GND
  DD51  VDDCR_CPU1_DD51  POWER  = PVDDCR_CPU1_P1
  DD52  VSS_DD52  POWER  = GND
  DD53  VSS_DD53  POWER  = GND
  DD54  VDDCR_CPU1_DD54  POWER  = PVDDCR_CPU1_P1
  DD55  MCB_DQS_H8  BI  = M_C_CPU1_SB_DQS_DP<8>
  DD56  MCB_DATA28  BI  = M_C_CPU1_SB_DQ<28>
  DD57  VSS_DD57  POWER  = GND
  DD58  MDB_DQS_H8  BI  = M_D_CPU1_SB_DQS_DP<8>
  DD59  VSS_DD59  POWER  = GND
  DD60  MDB_DATA28  BI  = M_D_CPU1_SB_DQ<28>
  DD61  VSS_DD61  POWER  = GND
  DD62  MBB_DQS_H8  BI  = M_B_CPU1_SB_DQS_DP<8>
  DD63  MBB_DATA28  BI  = M_B_CPU1_SB_DQ<28>
  DD64  VSS_DD64  POWER  = GND
  DD65  MFB_DQS_H8  BI  = M_F_CPU1_SB_DQS_DP<8>
  DD66  VSS_DD66  POWER  = GND
  DD67  MFB_DATA28  BI  = M_F_CPU1_SB_DQ<28>
  DD68  VSS_DD68  POWER  = GND
  DD69  MEB_DQS_H8  BI  = M_E_CPU1_SB_DQS_DP<8>
  DD70  MEB_DATA28  BI  = M_E_CPU1_SB_DQ<28>
  DD71  VSS_DD71  POWER  = GND
  DD72  MAB_DQS_H8  BI  = M_A_CPU1_SB_DQS_DP<8>
  DD73  VSS_DD73  POWER  = GND
  DD74  MAB_DATA28  BI  = M_A_CPU1_SB_DQ<28>
  DE1  VSS_DE1  POWER  = GND
  DE2  MGB_DATA30  BI  = M_G_CPU1_SB_DQ<30>
  DE3  MGB_DATA29  BI  = M_G_CPU1_SB_DQ<29>
  DE4  VDD_11_S3_DE4  POWER  = PVDD11_S3_P1
  DE5  MKB_DATA30  BI  = M_K_CPU1_SB_DQ<30>
  DE6  VSS_DE6  POWER  = GND
  DE7  MKB_DATA29  BI  = M_K_CPU1_SB_DQ<29>
  DE8  VSS_DE8  POWER  = GND
  DE9  MLB_DATA30  BI  = M_L_CPU1_SB_DQ<30>
  DE10  MLB_DATA29  BI  = M_L_CPU1_SB_DQ<29>
  DE11  VDD_11_S3_DE11  POWER  = PVDD11_S3_P1
  DE12  MHB_DATA30  BI  = M_H_CPU1_SB_DQ<30>
  DE13  VSS_DE13  POWER  = GND
  DE14  MHB_DATA29  BI  = M_H_CPU1_SB_DQ<29>
  DE15  VSS_DE15  POWER  = GND
  DE16  MJB_DATA30  BI  = M_J_CPU1_SB_DQ<30>
  DE17  MJB_DATA29  BI  = M_J_CPU1_SB_DQ<29>
  DE18  VDD_11_S3_DE18  POWER  = PVDD11_S3_P1
  DE19  MIB_DATA30  BI  = M_I_CPU1_SB_DQ<30>
  DE20  VSS_DE20  POWER  = GND
  DE21  MIB_DATA29  BI  = M_I_CPU1_SB_DQ<29>
  DE22  VDDCR_CPU1_DE22  POWER  = PVDDCR_CPU1_P1
  DE23  VSS_DE23  POWER  = GND
  DE24  \espi1_dat1||spi1_dat1||agpio132\  BI  = NC
  DE25  VDDCR_CPU1_DE25  POWER  = PVDDCR_CPU1_P1
  DE26  VSS_DE26  POWER  = GND
  DE27  \espi_rstout_l||agpio23\  BI  = NC
  DE28  VDDCR_CPU1_DE28  POWER  = PVDDCR_CPU1_P1
  DE29  VSS_DE29  POWER  = GND
  DE30  AGPIO105  BI  = NC
  DE31  VDDCR_CPU1_DE31  POWER  = PVDDCR_CPU1_P1
  DE32  AGPIO22  BI  = TP_SLOT2_BUF_SKU_ID1
  DE33  VSS_DE33  POWER  = GND
  DE34  VDDCR_CPU1_DE34  POWER  = PVDDCR_CPU1_P1
  DE35  VDDCR_CPU1_DE35  POWER  = PVDDCR_CPU1_P1
  DE36  \agpio3||spd_host_ctrl_l\  BI  = CPU1_SPD_HOST_CTRL_R_N
  DE40  \agpio6||devslp1||sata_zp1_l\  BI  = FM_BMC_READY_N
  DE41  VDDCR_CPU1_DE41  POWER  = PVDDCR_CPU1_P1
  DE42  VDDCR_CPU1_DE42  POWER  = PVDDCR_CPU1_P1
  DE43  P4_TXN3  OUT  = P3E_CPU1_P4_TX_DN<3>
  DE44  P4_TXP3  OUT  = P3E_CPU1_P4_TX_DP<3>
  DE45  VDDCR_CPU1_DE45  POWER  = PVDDCR_CPU1_P1
  DE46  P4_TXN2  OUT  = P3E_CPU1_P4_TX_DN<2>
  DE47  P4_TXP2  OUT  = P3E_CPU1_P4_TX_DP<2>
  DE48  VDDCR_CPU1_DE48  POWER  = PVDDCR_CPU1_P1
  DE49  P4_TXN1  OUT  = P3E_CPU1_P4_TX_DN<1>
  DE50  P4_TXP1  OUT  = P3E_CPU1_P4_TX_DP<1>
  DE51  VDDCR_CPU1_DE51  POWER  = PVDDCR_CPU1_P1
  DE52  P4_TXN0  OUT  = P3E_CPU1_P4_TX_DN<0>
  DE53  P4_TXP0  OUT  = P3E_CPU1_P4_TX_DP<0>
  DE54  VDDCR_CPU1_DE54  POWER  = PVDDCR_CPU1_P1
  DE55  MCB_DATA29  BI  = M_C_CPU1_SB_DQ<29>
  DE56  VSS_DE56  POWER  = GND
  DE57  MCB_DATA30  BI  = M_C_CPU1_SB_DQ<30>
  DE58  VDDIO_DE58  POWER  = PVDDIO_P1
  DE59  MDB_DATA29  BI  = M_D_CPU1_SB_DQ<29>
  DE60  MDB_DATA30  BI  = M_D_CPU1_SB_DQ<30>
  DE61  VSS_DE61  POWER  = GND
  DE62  MBB_DATA29  BI  = M_B_CPU1_SB_DQ<29>
  DE63  VSS_DE63  POWER  = GND
  DE64  MBB_DATA30  BI  = M_B_CPU1_SB_DQ<30>
  DE65  VDDIO_DE65  POWER  = PVDDIO_P1
  DE66  MFB_DATA29  BI  = M_F_CPU1_SB_DQ<29>
  DE67  MFB_DATA30  BI  = M_F_CPU1_SB_DQ<30>
  DE68  VSS_DE68  POWER  = GND
  DE69  MEB_DATA29  BI  = M_E_CPU1_SB_DQ<29>
  DE70  VSS_DE70  POWER  = GND
  DE71  MEB_DATA30  BI  = M_E_CPU1_SB_DQ<30>
  DE72  VDDIO_DE72  POWER  = PVDDIO_P1
  DE73  MAB_DATA29  BI  = M_A_CPU1_SB_DQ<29>
  DE74  MAB_DATA30  BI  = M_A_CPU1_SB_DQ<30>
  DE75  VSS_DE75  POWER  = GND
  DF2  MGB_DATA31  BI  = M_G_CPU1_SB_DQ<31>
  DF3  VSS_DF3  POWER  = GND
  DF4  VSS_DF4  POWER  = GND
  DF5  VSS_DF5  POWER  = GND
  DF6  VSS_DF6  POWER  = GND
  DF7  MKB_DATA31  BI  = M_K_CPU1_SB_DQ<31>
  DF8  VSS_DF8  POWER  = GND
  DF9  MLB_DATA31  BI  = M_L_CPU1_SB_DQ<31>
  DF10  VSS_DF10  POWER  = GND
  DF11  VSS_DF11  POWER  = GND
  DF12  VSS_DF12  POWER  = GND
  DF13  VSS_DF13  POWER  = GND
  DF14  MHB_DATA31  BI  = M_H_CPU1_SB_DQ<31>
  DF15  VSS_DF15  POWER  = GND
  DF16  MJB_DATA31  BI  = M_J_CPU1_SB_DQ<31>
  DF17  VSS_DF17  POWER  = GND
  DF18  VSS_DF18  POWER  = GND
  DF19  VSS_DF19  POWER  = GND
  DF20  VSS_DF20  POWER  = GND
  DF21  MIB_DATA31  BI  = M_I_CPU1_SB_DQ<31>
  DF22  VSS_DF22  POWER  = GND
  DF23  VSS_DF23  POWER  = GND
  DF24  \espi1_alert_l||agpio110\  BI  = NC
  DF25  \espi1_dat2||spi1_dat2||agpio133\  BI  = NC
  DF26  VSS_DF26  POWER  = GND
  DF27  \espi_clk2||agpio74\  BI  = PD_ESPI_CPU1_CLK2
  DF28  \espi0_dat0||spi0_dat0||agpio120\  BI  = NC
  DF29  VSS_DF29  POWER  = GND
  DF30  \spi_cs0_l||agpio118\  BI  = NC
  DF31  AGPIO106  BI  = NC
